# BASEBOARD_FAB2 (Tioga Pass) — schematic netlist excerpt (pin names and nets, part order shuffled) for the footprints in the layout excerpt that follows; sources: Cadence DE-HDL packaged netlist, KiCad conversion of Wiwynn_Tioga_Pass_MB.brd

R7F19  RES  1.00K 1% CHIP  pkg 0402  page 231 : A = P3V3_STBY ; B = PWRGD_PVPP_ABC_R
C7B1  CAP_A  1.0UF 6.3V 10% X6S  pkg 0402V  page 218 : A = VR_PVDDQ_DEF_VD12 ; B = GND
R7W4  RES  49.9 1% EMPTY  pkg 0402  page 92 : A = PVCCIO_CPU0 ; B = P0V7_GTL2104_VREF_0

(kicad_pcb
	(version 20260206)
	(generator "pcbnew")
	(generator_version "10.0")
	(general
		(thickness 1.6)
		(legacy_teardrops no)
	)
	(paper "A4")
	(title_block
		(title "Wiwynn_Tioga_Pass_MB.brd")
		(comment 1 "Tioga Pass / footprints 2186-2188 of 4770")
	)
	(layers
		(0 "F.Cu" signal "TOP")
		(4 "In1.Cu" signal "L2GND")
		(6 "In2.Cu" signal "L3")
		(8 "In3.Cu" signal "L4GND")
		(10 "In4.Cu" signal "L5")
		(12 "In5.Cu" signal "L6GND")
		(14 "In6.Cu" signal "L7VCC")
		(16 "In7.Cu" signal "L8VCC")
		(18 "In8.Cu" signal "L9GND")
		(20 "In9.Cu" signal "L10")
		(22 "In10.Cu" signal "L11GND")
		(24 "In11.Cu" signal "L12")
		(26 "In12.Cu" signal "L13GND")
		(2 "B.Cu" signal "BOTTOM")
		(9 "F.Adhes" user "F.Adhesive")
		(11 "B.Adhes" user "B.Adhesive")
		(13 "F.Paste" user "Package Geometry/Pastemask Top")
		(15 "B.Paste" user "Package Geometry/Pastemask Bottom")
		(5 "F.SilkS" user "Ref Des/Silkscreen Top")
		(7 "B.SilkS" user "Ref Des/Silkscreen Bottom")
		(1 "F.Mask" user "Board Geometry/Soldermask Top")
		(3 "B.Mask" user "Board Geometry/Soldermask Bottom")
		(17 "Dwgs.User" user "User.Drawings")
		(19 "Cmts.User" user "User.Comments")
		(21 "Eco1.User" user "User.Eco1")
		(23 "Eco2.User" user "User.Eco2")
		(25 "Edge.Cuts" user "Board Geometry/Outline")
		(27 "Margin" user)
		(31 "F.CrtYd" user "Package Geometry/Place Bound Top")
		(29 "B.CrtYd" user "Package Geometry/Place Bound Bottom")
		(35 "F.Fab" user "Ref Des/Assembly Top")
		(33 "B.Fab" user "Ref Des/Assembly Bottom")
	)
	(footprint ""
		(layer "F.Cu")
		(at 356.09784 -134.22757)
		(property "Reference" "C7B1"
			(at 0 0 0)
			(layer "F.SilkS")
			(hide yes)
			(effects
				(font
					(size 1.27 1.27)
				)
			)
		)
		(property "Value" ""
			(at 0 0 0)
			(layer "F.Fab")
			(effects
				(font
					(size 1.27 1.27)
				)
			)
		)
		(duplicate_pad_numbers_are_jumpers no)
		(fp_poly
			(pts
				(xy 0.3048 -0.1016) (xy 0.3048 0.9906) (xy -0.3048 0.9906) (xy -0.3048 -0.1016)
			)
			(stroke
				(width 0)
				(type default)
			)
			(fill no)
			(layer "F.CrtYd")
		)
		(fp_line
			(start -0.3048 -0.1016)
			(end -0.3048 0.9906)
			(stroke
				(width 0.1)
				(type default)
			)
			(layer "F.Fab")
		)
		(fp_line
			(start -0.3048 0.9906)
			(end 0.3048 0.9906)
			(stroke
				(width 0.1)
				(type default)
			)
			(layer "F.Fab")
		)
		(fp_line
			(start 0.3048 -0.1016)
			(end -0.3048 -0.1016)
			(stroke
				(width 0.1)
				(type default)
			)
			(layer "F.Fab")
		)
		(fp_line
			(start 0.3048 0.9906)
			(end 0.3048 -0.1016)
			(stroke
				(width 0.1)
				(type default)
			)
			(layer "F.Fab")
		)
		(pad "1" smd rect
			(at 0 0)
			(size 0.508 0.508)
			(layers "F.Cu" "F.Mask" "F.Paste")
			(net "VR_PVDDQ_DEF_VD12")
		)
		(pad "2" smd rect
			(at 0 0.889)
			(size 0.508 0.508)
			(layers "F.Cu" "F.Mask" "F.Paste")
			(net "GND")
		)
		(zone
			(layer "F.Cu")
			(hatch none 0.5)
			(connect_pads
				(clearance 0)
			)
			(min_thickness 0.25)
			(keepout
				(tracks allowed)
				(vias not_allowed)
				(pads allowed)
				(copperpour not_allowed)
				(footprints allowed)
			)
			(placement
				(enabled no)
				(sheetname "")
			)
			(fill
				(thermal_gap 0.5)
				(thermal_bridge_width 0.5)
				(island_removal_mode 0)
			)
			(polygon
				(pts
					(xy 355.84384 -133.97357) (xy 356.35184 -133.97357) (xy 356.35184 -133.59257) (xy 355.84384 -133.59257)
				)
			)
		)
		(zone
			(layer "F.Cu")
			(hatch none 0.5)
			(connect_pads
				(clearance 0)
			)
			(min_thickness 0.25)
			(keepout
				(tracks not_allowed)
				(vias allowed)
				(pads allowed)
				(copperpour not_allowed)
				(footprints allowed)
			)
			(placement
				(enabled no)
				(sheetname "")
			)
			(fill
				(thermal_gap 0.5)
				(thermal_bridge_width 0.5)
				(island_removal_mode 0)
			)
			(polygon
				(pts
					(xy 355.84384 -133.59257) (xy 356.35184 -133.59257) (xy 356.35184 -133.97357) (xy 355.84384 -133.97357)
				)
			)
		)
	)
	(footprint ""
		(layer "F.Cu")
		(at 389.9535 -79.8322 180)
		(property "Reference" "R7W4"
			(at -0.8382 -0.67818 180)
			(unlocked yes)
			(layer "F.SilkS")
			(effects
				(font
					(size 0.4064 0.254)
					(thickness 0.1524)
				)
				(justify left)
			)
		)
		(property "Value" ""
			(at 0 0 180)
			(layer "F.Fab")
			(effects
				(font
					(size 1.27 1.27)
				)
			)
		)
		(duplicate_pad_numbers_are_jumpers no)
		(fp_poly
			(pts
				(xy -0.2794 -0.1016) (xy 0.2794 -0.1016) (xy 0.2794 0.9906) (xy -0.2794 0.9906)
			)
			(stroke
				(width 0)
				(type default)
			)
			(fill no)
			(layer "F.CrtYd")
		)
		(fp_line
			(start 0.2794 0.9906)
			(end 0.2794 -0.1016)
			(stroke
				(width 0.1)
				(type default)
			)
			(layer "F.Fab")
		)
		(fp_line
			(start 0.2794 -0.1016)
			(end -0.2794 -0.1016)
			(stroke
				(width 0.1)
				(type default)
			)
			(layer "F.Fab")
		)
		(fp_line
			(start -0.2794 0.9906)
			(end 0.2794 0.9906)
			(stroke
				(width 0.1)
				(type default)
			)
			(layer "F.Fab")
		)
		(fp_line
			(start -0.2794 -0.1016)
			(end -0.2794 0.9906)
			(stroke
				(width 0.1)
				(type default)
			)
			(layer "F.Fab")
		)
		(pad "1" smd rect
			(at 0 0 180)
			(size 0.508 0.508)
			(layers "F.Cu" "F.Mask" "F.Paste")
			(net "PVCCIO_CPU0")
		)
		(pad "2" smd rect
			(at 0 0.889 180)
			(size 0.508 0.508)
			(layers "F.Cu" "F.Mask" "F.Paste")
			(net "P0V7_GTL2104_VREF_0")
		)
		(zone
			(layer "F.Cu")
			(hatch none 0.5)
			(connect_pads
				(clearance 0)
			)
			(min_thickness 0.25)
			(keepout
				(tracks not_allowed)
				(vias allowed)
				(pads allowed)
				(copperpour not_allowed)
				(footprints allowed)
			)
			(placement
				(enabled no)
				(sheetname "")
			)
			(fill
				(thermal_gap 0.5)
				(thermal_bridge_width 0.5)
				(island_removal_mode 0)
			)
			(polygon
				(pts
					(xy 390.2075 -80.4672) (xy 389.6995 -80.4672) (xy 389.6995 -80.0862) (xy 390.2075 -80.0862)
				)
			)
		)
		(zone
			(layer "F.Cu")
			(hatch none 0.5)
			(connect_pads
				(clearance 0)
			)
			(min_thickness 0.25)
			(keepout
				(tracks allowed)
				(vias not_allowed)
				(pads allowed)
				(copperpour not_allowed)
				(footprints allowed)
			)
			(placement
				(enabled no)
				(sheetname "")
			)
			(fill
				(thermal_gap 0.5)
				(thermal_bridge_width 0.5)
				(island_removal_mode 0)
			)
			(polygon
				(pts
					(xy 390.2075 -80.0862) (xy 389.6995 -80.0862) (xy 389.6995 -80.4672) (xy 390.2075 -80.4672)
				)
			)
		)
	)
	(footprint ""
		(layer "F.Cu")
		(at 347.622114 -22.5933 180)
		(property "Reference" "R7F19"
			(at 0 0 180)
			(layer "F.SilkS")
			(hide yes)
			(effects
				(font
					(size 1.27 1.27)
				)
			)
		)
		(property "Value" ""
			(at 0 0 180)
			(layer "F.Fab")
			(effects
				(font
					(size 1.27 1.27)
				)
			)
		)
		(duplicate_pad_numbers_are_jumpers no)
		(fp_rect
			(start 0.2794 -0.1016)
			(end -0.2794 0.9906)
			(stroke
				(width 0)
				(type default)
			)
			(fill no)
			(layer "F.CrtYd")
		)
		(fp_line
			(start 0.2794 0.9906)
			(end 0.2794 -0.1016)
			(stroke
				(width 0.1)
				(type default)
			)
			(layer "F.Fab")
		)
		(fp_line
			(start 0.2794 -0.1016)
			(end -0.2794 -0.1016)
			(stroke
				(width 0.1)
				(type default)
			)
			(layer "F.Fab")
		)
		(fp_line
			(start -0.2794 0.9906)
			(end 0.2794 0.9906)
			(stroke
				(width 0.1)
				(type default)
			)
			(layer "F.Fab")
		)
		(fp_line
			(start -0.2794 -0.1016)
			(end -0.2794 0.9906)
			(stroke
				(width 0.1)
				(type default)
			)
			(layer "F.Fab")
		)
		(pad "1" smd rect
			(at 0 0 180)
			(size 0.508 0.508)
			(layers "F.Cu" "F.Mask" "F.Paste")
			(net "P3V3_STBY")
		)
		(pad "2" smd rect
			(at 0 0.889 180)
			(size 0.508 0.508)
			(layers "F.Cu" "F.Mask" "F.Paste")
			(net "PWRGD_PVPP_ABC_R")
		)
		(zone
			(layer "F.Cu")
			(hatch none 0.5)
			(connect_pads
				(clearance 0)
			)
			(min_thickness 0.25)
			(keepout
				(tracks not_allowed)
				(vias allowed)
				(pads allowed)
				(copperpour not_allowed)
				(footprints allowed)
			)
			(placement
				(enabled no)
				(sheetname "")
			)
			(fill
				(thermal_gap 0.5)
				(thermal_bridge_width 0.5)
				(island_removal_mode 0)
			)
			(polygon
				(pts
					(xy 347.368114 -22.8473) (xy 347.876114 -22.8473) (xy 347.876114 -23.2283) (xy 347.368114 -23.2283)
				)
			)
		)
		(zone
			(layer "F.Cu")
			(hatch none 0.5)
			(connect_pads
				(clearance 0)
			)
			(min_thickness 0.25)
			(keepout
				(tracks allowed)
				(vias not_allowed)
				(pads allowed)
				(copperpour not_allowed)
				(footprints allowed)
			)
			(placement
				(enabled no)
				(sheetname "")
			)
			(fill
				(thermal_gap 0.5)
				(thermal_bridge_width 0.5)
				(island_removal_mode 0)
			)
			(polygon
				(pts
					(xy 347.368114 -22.8473) (xy 347.876114 -22.8473) (xy 347.876114 -23.2283) (xy 347.368114 -23.2283)
				)
			)
		)
	)
)
